# T6G (Grand Teton) — schematic netlist excerpt (pin names and nets, part order shuffled) for the footprints in the layout excerpt that follows; sources: Cadence DE-HDL packaged netlist, KiCad conversion of 04192023_DAF0TMB3IC0_F0TG_MB_C_brd_V02_OCP.brd

C2622  Q_CAP  22UF 4V 20% X6S  pkg C0402  page 70 : A = PVDD11_S3_P0 ; B = GND
C87  Q_CAP  0.001UF 50V 10% X7R  pkg C0402  page 172 : A = HDT_HDR_DBREQ_N ; B = GND

(kicad_pcb
	(version 20260206)
	(generator "pcbnew")
	(generator_version "10.0")
	(general
		(thickness 1.6)
		(legacy_teardrops no)
	)
	(paper "A4")
	(title_block
		(title "04192023_DAF0TMB3IC0_F0TG_MB_C_brd_V02_OCP.brd")
		(comment 1 "Grand Teton / footprints 1724-1725 of 8354")
	)
	(layers
		(0 "F.Cu" signal "TOP")
		(4 "In1.Cu" signal "GND")
		(6 "In2.Cu" signal "IN1")
		(8 "In3.Cu" signal "GND1")
		(10 "In4.Cu" signal "IN2")
		(12 "In5.Cu" signal "GND2")
		(14 "In6.Cu" signal "IN3")
		(16 "In7.Cu" signal "GND3")
		(18 "In8.Cu" signal "VCC")
		(20 "In9.Cu" signal "VCC1")
		(22 "In10.Cu" signal "GND4")
		(24 "In11.Cu" signal "IN4")
		(26 "In12.Cu" signal "GND5")
		(28 "In13.Cu" signal "IN5")
		(30 "In14.Cu" signal "GND6")
		(32 "In15.Cu" signal "IN6")
		(34 "In16.Cu" signal "GND7")
		(2 "B.Cu" signal "BOTTOM")
		(9 "F.Adhes" user "F.Adhesive")
		(11 "B.Adhes" user "B.Adhesive")
		(13 "F.Paste" user "Package Geometry/Pastemask Top")
		(15 "B.Paste" user "Package Geometry/Pastemask Bottom")
		(5 "F.SilkS" user "Ref Des/Silkscreen Top")
		(7 "B.SilkS" user "Ref Des/Silkscreen Bottom")
		(1 "F.Mask" user "Board Geometry/Soldermask Top")
		(3 "B.Mask" user "Board Geometry/Soldermask Bottom")
		(17 "Dwgs.User" user "User.Drawings")
		(19 "Cmts.User" user "User.Comments")
		(21 "Eco1.User" user "User.Eco1")
		(23 "Eco2.User" user "User.Eco2")
		(25 "Edge.Cuts" user "Board Geometry/Outline")
		(27 "Margin" user)
		(31 "F.CrtYd" user "Package Geometry/Place Bound Top")
		(29 "B.CrtYd" user "Package Geometry/Place Bound Bottom")
		(35 "F.Fab" user "Ref Des/Assembly Top")
		(33 "B.Fab" user "Ref Des/Assembly Bottom")
	)
	(footprint ""
		(layer "F.Cu")
		(at 384.465576 -62.97295 90)
		(property "Reference" "C87"
			(at 0 0 90)
			(layer "F.SilkS")
			(hide yes)
			(effects
				(font
					(size 1.27 1.27)
				)
			)
		)
		(property "Value" ""
			(at 0 0 90)
			(layer "F.Fab")
			(effects
				(font
					(size 1.27 1.27)
				)
			)
		)
		(duplicate_pad_numbers_are_jumpers no)
		(fp_line
			(start 0.7874 -0.4064)
			(end 0.7874 0.4064)
			(stroke
				(width 0.1524)
				(type default)
			)
			(layer "F.SilkS")
		)
		(fp_line
			(start -0.7874 -0.4064)
			(end 0.7874 -0.4064)
			(stroke
				(width 0.1524)
				(type default)
			)
			(layer "F.SilkS")
		)
		(fp_line
			(start 0.7874 0.4064)
			(end -0.7874 0.4064)
			(stroke
				(width 0.1524)
				(type default)
			)
			(layer "F.SilkS")
		)
		(fp_line
			(start -0.7874 0.4064)
			(end -0.7874 -0.4064)
			(stroke
				(width 0.1524)
				(type default)
			)
			(layer "F.SilkS")
		)
		(fp_line
			(start -0.12065 -0.305054)
			(end -0.12065 -0.2794)
			(stroke
				(width 0.1)
				(type default)
			)
			(layer "F.Fab")
		)
		(fp_line
			(start -0.67945 -0.305054)
			(end -0.12065 -0.305054)
			(stroke
				(width 0.1)
				(type default)
			)
			(layer "F.Fab")
		)
		(fp_line
			(start 0.67945 -0.3048)
			(end 0.67945 0.3048)
			(stroke
				(width 0.1)
				(type default)
			)
			(layer "F.Fab")
		)
		(fp_line
			(start 0.12065 -0.3048)
			(end 0.67945 -0.3048)
			(stroke
				(width 0.1)
				(type default)
			)
			(layer "F.Fab")
		)
		(fp_line
			(start 0.12065 -0.2794)
			(end 0.12065 -0.3048)
			(stroke
				(width 0.1)
				(type default)
			)
			(layer "F.Fab")
		)
		(fp_line
			(start -0.12065 -0.2794)
			(end 0.12065 -0.2794)
			(stroke
				(width 0.1)
				(type default)
			)
			(layer "F.Fab")
		)
		(fp_line
			(start 0.120396 0.2794)
			(end -0.12065 0.2794)
			(stroke
				(width 0.1)
				(type default)
			)
			(layer "F.Fab")
		)
		(fp_line
			(start -0.12065 0.2794)
			(end -0.12065 0.3048)
			(stroke
				(width 0.1)
				(type default)
			)
			(layer "F.Fab")
		)
		(fp_line
			(start 0.67945 0.3048)
			(end 0.120396 0.3048)
			(stroke
				(width 0.1)
				(type default)
			)
			(layer "F.Fab")
		)
		(fp_line
			(start 0.120396 0.3048)
			(end 0.120396 0.2794)
			(stroke
				(width 0.1)
				(type default)
			)
			(layer "F.Fab")
		)
		(fp_line
			(start -0.12065 0.3048)
			(end -0.67945 0.3048)
			(stroke
				(width 0.1)
				(type default)
			)
			(layer "F.Fab")
		)
		(fp_line
			(start -0.67945 0.3048)
			(end -0.67945 -0.305054)
			(stroke
				(width 0.1)
				(type default)
			)
			(layer "F.Fab")
		)
		(pad "1" smd circle
			(at -0.40005 0 90)
			(size 0 0)
			(layers "F.Cu" "F.Mask" "F.Paste")
			(net "HDT_HDR_DBREQ_N")
		)
		(pad "2" smd circle
			(at 0.40005 0 90)
			(size 0 0)
			(layers "F.Cu" "F.Mask" "F.Paste")
			(net "GND")
		)
	)
	(footprint ""
		(layer "F.Cu")
		(at 362.267246 -261.747762 -90)
		(property "Reference" "C2622"
			(at 0 0 270)
			(layer "F.SilkS")
			(hide yes)
			(effects
				(font
					(size 1.27 1.27)
				)
			)
		)
		(property "Value" ""
			(at 0 0 270)
			(layer "F.Fab")
			(effects
				(font
					(size 1.27 1.27)
				)
			)
		)
		(duplicate_pad_numbers_are_jumpers no)
		(fp_line
			(start -0.7874 0.4064)
			(end -0.7874 -0.4064)
			(stroke
				(width 0.1524)
				(type default)
			)
			(layer "F.SilkS")
		)
		(fp_line
			(start 0.7874 0.4064)
			(end -0.7874 0.4064)
			(stroke
				(width 0.1524)
				(type default)
			)
			(layer "F.SilkS")
		)
		(fp_line
			(start -0.7874 -0.4064)
			(end 0.7874 -0.4064)
			(stroke
				(width 0.1524)
				(type default)
			)
			(layer "F.SilkS")
		)
		(fp_line
			(start 0.7874 -0.4064)
			(end 0.7874 0.4064)
			(stroke
				(width 0.1524)
				(type default)
			)
			(layer "F.SilkS")
		)
		(fp_line
			(start -0.67945 0.3048)
			(end -0.67945 -0.305054)
			(stroke
				(width 0.1)
				(type default)
			)
			(layer "F.Fab")
		)
		(fp_line
			(start -0.12065 0.3048)
			(end -0.67945 0.3048)
			(stroke
				(width 0.1)
				(type default)
			)
			(layer "F.Fab")
		)
		(fp_line
			(start 0.120396 0.3048)
			(end 0.120396 0.2794)
			(stroke
				(width 0.1)
				(type default)
			)
			(layer "F.Fab")
		)
		(fp_line
			(start 0.67945 0.3048)
			(end 0.120396 0.3048)
			(stroke
				(width 0.1)
				(type default)
			)
			(layer "F.Fab")
		)
		(fp_line
			(start -0.12065 0.2794)
			(end -0.12065 0.3048)
			(stroke
				(width 0.1)
				(type default)
			)
			(layer "F.Fab")
		)
		(fp_line
			(start 0.120396 0.2794)
			(end -0.12065 0.2794)
			(stroke
				(width 0.1)
				(type default)
			)
			(layer "F.Fab")
		)
		(fp_line
			(start -0.12065 -0.2794)
			(end 0.12065 -0.2794)
			(stroke
				(width 0.1)
				(type default)
			)
			(layer "F.Fab")
		)
		(fp_line
			(start 0.12065 -0.2794)
			(end 0.12065 -0.3048)
			(stroke
				(width 0.1)
				(type default)
			)
			(layer "F.Fab")
		)
		(fp_line
			(start 0.12065 -0.3048)
			(end 0.67945 -0.3048)
			(stroke
				(width 0.1)
				(type default)
			)
			(layer "F.Fab")
		)
		(fp_line
			(start 0.67945 -0.3048)
			(end 0.67945 0.3048)
			(stroke
				(width 0.1)
				(type default)
			)
			(layer "F.Fab")
		)
		(fp_line
			(start -0.67945 -0.305054)
			(end -0.12065 -0.305054)
			(stroke
				(width 0.1)
				(type default)
			)
			(layer "F.Fab")
		)
		(fp_line
			(start -0.12065 -0.305054)
			(end -0.12065 -0.2794)
			(stroke
				(width 0.1)
				(type default)
			)
			(layer "F.Fab")
		)
		(pad "1" smd circle
			(at -0.40005 0 270)
			(size 0 0)
			(layers "F.Cu" "F.Mask" "F.Paste")
			(net "PVDD11_S3_P0")
		)
		(pad "2" smd circle
			(at 0.40005 0 270)
			(size 0 0)
			(layers "F.Cu" "F.Mask" "F.Paste")
			(net "GND")
		)
	)
)
